FILE_TYPE = CONNECTIVITY;
{Allegro Design Entry HDL 17.2-2016 S081 (4005846) 1/11/2022}
"PAGE_NUMBER" = 127;
0"NC";
1"P3V3_AUX\g";
2"P3V3_AUX\g";
3"P3V3_AUX\g";
4"P3V3_AUX\g";
5"GND\g";
6"GND\g";
7"GND\g";
8"GND\g";
9"GND\g";
10"GND\g";
11"GND\g";
12"GND\g";
13"PU_PIROM_CPU1_SM_WP";
14"PU_PIROM_CPU0_SM_WP";
15"PD_PIROM_CPU1_ADDR2";
16"PD_PIROM_CPU0_ADDR2";
17"PD_PIROM_CPU1_ADDR1";
18"PU_PIROM_CPU1_ADDR0";
19"PD_PIROM_CPU0_ADDR1";
20"PD_PIROM_CPU0_ADDR0";
%"Q_RES"
"2","(-1900,2975)","0","pure_quanta","I1";
;
PART_NUMBER"CS31002FB08"
VALUE"10K"
WATTAGE"1/16W"
TOLERANCE"1%"
PACK_TYPE"0402LF"
MATERIAL"CHIP"
$LOCATION"R334"
CDS_LIB"pure_quanta"
CDS_LOCATION"R334"
$SEC"1"
CDS_SEC"1";
"A"
$PN"1"19;
"B"
$PN"2"5;
%"Q_RES"
"2","(1625,3625)","0","pure_quanta","I13";
;
PART_NUMBER"CS21002FB06"
PACK_TYPE"0402LF"
MATERIAL"CHIP"
WATTAGE"1/16W"
VALUE"1K"
TOLERANCE"1%"
$LOCATION"R629"
CDS_LIB"pure_quanta"
CDS_LOCATION"R629"
$SEC"1"
CDS_SEC"1";
"A"
$PN"1"3;
"B"
$PN"2"18;
%"Q_RES"
"2","(1350,3625)","0","pure_quanta","I14";
;
PART_NUMBER"CS21002FB06"
PACK_TYPE"0402LF"
MATERIAL"EMPTY"
VALUE"1K"
WATTAGE"1/16W"
TOLERANCE"1%"
$LOCATION"R627"
CDS_LIB"pure_quanta"
CDS_LOCATION"R627"
$SEC"1"
CDS_SEC"1";
"A"
$PN"1"3;
"B"
$PN"2"17;
%"Q_RES"
"2","(1625,2975)","0","pure_quanta","I15";
;
PART_NUMBER"CS31002FB08"
VALUE"10K"
MATERIAL"EMPTY"
WATTAGE"1/16W"
PACK_TYPE"0402LF"
TOLERANCE"1%"
$LOCATION"R630"
CDS_LIB"pure_quanta"
CDS_LOCATION"R630"
$SEC"1"
CDS_SEC"1";
"A"
$PN"1"18;
"B"
$PN"2"12;
%"UNIVERSAL_GND"
"1","(1625,2750)","0","logical_power","I16";
;
CDS_LIB"logical_power"
HDL_POWER"GND";
"A"12;
%"Q_RES"
"2","(1350,2975)","0","pure_quanta","I17";
;
PART_NUMBER"CS31002FB08"
TOLERANCE"1%"
WATTAGE"1/16W"
MATERIAL"CHIP"
VALUE"10K"
PACK_TYPE"0402LF"
$LOCATION"R628"
CDS_LIB"pure_quanta"
CDS_LOCATION"R628"
$SEC"1"
CDS_SEC"1";
"A"
$PN"1"17;
"B"
$PN"2"11;
%"UNIVERSAL_GND"
"1","(1350,2750)","0","logical_power","I18";
;
CDS_LIB"logical_power"
HDL_POWER"GND";
"A"11;
%"UNIVERSAL_POWER"
"1","(-2175,4000)","0","logical_power","I19";
;
HDL_POWER"P3V3_AUX"
CDS_LIB"logical_power";
"A"4;
%"Q_RES"
"2","(-2175,3625)","0","pure_quanta","I20";
;
PART_NUMBER"CS21002FB06"
PACK_TYPE"0402LF"
VALUE"1K"
WATTAGE"1/16W"
TOLERANCE"1%"
MATERIAL"EMPTY"
$LOCATION"R331"
CDS_LIB"pure_quanta"
CDS_LOCATION"R331"
$SEC"1"
CDS_SEC"1";
"A"
$PN"1"4;
"B"
$PN"2"16;
%"Q_RES"
"2","(-2175,2975)","0","pure_quanta","I21";
;
PART_NUMBER"CS31002FB08"
WATTAGE"1/16W"
MATERIAL"CHIP"
VALUE"10K"
TOLERANCE"1%"
PACK_TYPE"0402LF"
$LOCATION"R332"
CDS_LIB"pure_quanta"
CDS_LOCATION"R332"
$SEC"1"
CDS_SEC"1";
"A"
$PN"1"16;
"B"
$PN"2"10;
%"UNIVERSAL_GND"
"1","(-2175,2750)","0","logical_power","I22";
;
CDS_LIB"logical_power"
HDL_POWER"GND";
"A"10;
%"UNIVERSAL_POWER"
"1","(1075,3975)","0","logical_power","I23";
;
HDL_POWER"P3V3_AUX"
CDS_LIB"logical_power";
"A"3;
%"Q_RES"
"2","(1075,3625)","0","pure_quanta","I24";
;
PART_NUMBER"CS21002FB06"
MATERIAL"EMPTY"
TOLERANCE"1%"
WATTAGE"1/16W"
PACK_TYPE"0402LF"
VALUE"1K"
$LOCATION"R625"
CDS_LIB"pure_quanta"
CDS_LOCATION"R625"
$SEC"1"
CDS_SEC"1";
"A"
$PN"1"3;
"B"
$PN"2"15;
%"UNIVERSAL_GND"
"1","(1075,2750)","0","logical_power","I25";
;
CDS_LIB"logical_power"
HDL_POWER"GND";
"A"9;
%"Q_RES"
"2","(1075,2975)","0","pure_quanta","I26";
;
PART_NUMBER"CS31002FB08"
MATERIAL"CHIP"
WATTAGE"1/16W"
TOLERANCE"1%"
VALUE"10K"
PACK_TYPE"0402LF"
$LOCATION"R626"
CDS_LIB"pure_quanta"
CDS_LOCATION"R626"
$SEC"1"
CDS_SEC"1";
"A"
$PN"1"15;
"B"
$PN"2"9;
%"UNIVERSAL_POWER"
"1","(-2175,2300)","0","logical_power","I28";
;
HDL_POWER"P3V3_AUX"
CDS_LIB"logical_power";
"A"2;
%"UNIVERSAL_GND"
"1","(-2175,1250)","0","logical_power","I30";
;
CDS_LIB"logical_power"
HDL_POWER"GND";
"A"8;
%"Q_RES"
"2","(-2175,1475)","0","pure_quanta","I31";
;
PART_NUMBER"CS31002FB08"
WATTAGE"1/16W"
PACK_TYPE"0402LF"
TOLERANCE"1%"
VALUE"10K"
MATERIAL"EMPTY"
$LOCATION"R997"
CDS_LIB"pure_quanta"
CDS_LOCATION"R997"
$SEC"1"
CDS_SEC"1";
"A"
$PN"1"14;
"B"
$PN"2"8;
%"Q_RES"
"2","(-2175,2000)","0","pure_quanta","I32";
;
PART_NUMBER"CS21002FB06"
PACK_TYPE"0402LF"
VALUE"1K"
WATTAGE"1/16W"
TOLERANCE"1%"
MATERIAL"CHIP"
$LOCATION"R650"
CDS_LIB"pure_quanta"
CDS_LOCATION"R650"
$SEC"1"
CDS_SEC"1";
"A"
$PN"1"2;
"B"
$PN"2"14;
%"UNIVERSAL_POWER"
"1","(1075,2300)","0","logical_power","I34";
;
HDL_POWER"P3V3_AUX"
CDS_LIB"logical_power";
"A"1;
%"Q_RES"
"2","(1075,2000)","0","pure_quanta","I35";
;
PART_NUMBER"CS21002FB06"
PACK_TYPE"0402LF"
TOLERANCE"1%"
WATTAGE"1/16W"
VALUE"1K"
MATERIAL"CHIP"
$LOCATION"R1004"
CDS_LIB"pure_quanta"
CDS_LOCATION"R1004"
$SEC"1"
CDS_SEC"1";
"A"
$PN"1"1;
"B"
$PN"2"13;
%"Q_RES"
"2","(1075,1475)","0","pure_quanta","I36";
;
PART_NUMBER"CS31002FB08"
VALUE"10K"
WATTAGE"1/16W"
TOLERANCE"1%"
PACK_TYPE"0402LF"
MATERIAL"EMPTY"
$LOCATION"R1005"
CDS_LIB"pure_quanta"
CDS_LOCATION"R1005"
$SEC"1"
CDS_SEC"1";
"A"
$PN"1"13;
"B"
$PN"2"7;
%"UNIVERSAL_GND"
"1","(1075,1250)","0","logical_power","I37";
;
CDS_LIB"logical_power"
HDL_POWER"GND";
"A"7;
%"Q_RES"
"2","(-1625,3625)","0","pure_quanta","I5";
;
PART_NUMBER"CS21002FB06"
VALUE"1K"
TOLERANCE"1%"
WATTAGE"1/16W"
PACK_TYPE"0402LF"
MATERIAL"EMPTY"
$LOCATION"R335"
CDS_LIB"pure_quanta"
CDS_LOCATION"R335"
$SEC"1"
CDS_SEC"1";
"A"
$PN"1"4;
"B"
$PN"2"20;
%"Q_RES"
"2","(-1900,3625)","0","pure_quanta","I6";
;
PART_NUMBER"CS21002FB06"
VALUE"1K"
MATERIAL"EMPTY"
TOLERANCE"1%"
WATTAGE"1/16W"
PACK_TYPE"0402LF"
$LOCATION"R333"
CDS_LIB"pure_quanta"
CDS_LOCATION"R333"
$SEC"1"
CDS_SEC"1";
"A"
$PN"1"4;
"B"
$PN"2"19;
%"Q_RES"
"2","(-1625,2975)","0","pure_quanta","I7";
;
PART_NUMBER"CS31002FB08"
PACK_TYPE"0402LF"
TOLERANCE"1%"
WATTAGE"1/16W"
MATERIAL"CHIP"
VALUE"10K"
$LOCATION"R515"
CDS_LIB"pure_quanta"
CDS_LOCATION"R515"
$SEC"1"
CDS_SEC"1";
"A"
$PN"1"20;
"B"
$PN"2"6;
%"UNIVERSAL_GND"
"1","(-1625,2750)","0","logical_power","I8";
;
CDS_LIB"logical_power"
HDL_POWER"GND";
"A"6;
%"UNIVERSAL_GND"
"1","(-1900,2750)","0","logical_power","I9";
;
CDS_LIB"logical_power"
HDL_POWER"GND";
"A"5;
END.
